# BASEBOARD_FAB2 (Tioga Pass) — schematic netlist excerpt (pin names and nets, part order shuffled) for the footprints in the layout excerpt that follows; sources: Cadence DE-HDL packaged netlist, KiCad conversion of Wiwynn_Tioga_Pass_MB.brd

R8P2  RES  49.9 1% CHIP  pkg 0402  page 90 : A = PD_CPU1_TEST13 ; B = GND
R2U43  RES  1.00K 1% CHIP  pkg 0402  page 196 : A = P3V_BAT_SOURCE ; B = A_P3V_BAT_R
C2U2  CAP  10UF 16V 10% X6S  pkg 0805  page 198 : A = P3V3 ; B = GND

(kicad_pcb
	(version 20260206)
	(generator "pcbnew")
	(generator_version "10.0")
	(general
		(thickness 1.6)
		(legacy_teardrops no)
	)
	(paper "A4")
	(title_block
		(title "Wiwynn_Tioga_Pass_MB.brd")
		(comment 1 "Tioga Pass / footprints 3996-3998 of 4770")
	)
	(layers
		(0 "F.Cu" signal "TOP")
		(4 "In1.Cu" signal "L2GND")
		(6 "In2.Cu" signal "L3")
		(8 "In3.Cu" signal "L4GND")
		(10 "In4.Cu" signal "L5")
		(12 "In5.Cu" signal "L6GND")
		(14 "In6.Cu" signal "L7VCC")
		(16 "In7.Cu" signal "L8VCC")
		(18 "In8.Cu" signal "L9GND")
		(20 "In9.Cu" signal "L10")
		(22 "In10.Cu" signal "L11GND")
		(24 "In11.Cu" signal "L12")
		(26 "In12.Cu" signal "L13GND")
		(2 "B.Cu" signal "BOTTOM")
		(9 "F.Adhes" user "F.Adhesive")
		(11 "B.Adhes" user "B.Adhesive")
		(13 "F.Paste" user "Package Geometry/Pastemask Top")
		(15 "B.Paste" user "Package Geometry/Pastemask Bottom")
		(5 "F.SilkS" user "Ref Des/Silkscreen Top")
		(7 "B.SilkS" user "Ref Des/Silkscreen Bottom")
		(1 "F.Mask" user "Board Geometry/Soldermask Top")
		(3 "B.Mask" user "Board Geometry/Soldermask Bottom")
		(17 "Dwgs.User" user "User.Drawings")
		(19 "Cmts.User" user "User.Comments")
		(21 "Eco1.User" user "User.Eco1")
		(23 "Eco2.User" user "User.Eco2")
		(25 "Edge.Cuts" user "Board Geometry/Outline")
		(27 "Margin" user)
		(31 "F.CrtYd" user "Package Geometry/Place Bound Top")
		(29 "B.CrtYd" user "Package Geometry/Place Bound Bottom")
		(35 "F.Fab" user "Ref Des/Assembly Top")
		(33 "B.Fab" user "Ref Des/Assembly Bottom")
	)
	(footprint ""
		(layer "B.Cu")
		(at 449.9864 -8.0518 -90)
		(property "Reference" "R2U43"
			(at 0 0 90)
			(layer "B.SilkS")
			(hide yes)
			(effects
				(font
					(size 1.27 1.27)
				)
				(justify mirror)
			)
		)
		(property "Value" ""
			(at 0 0 90)
			(layer "B.Fab")
			(effects
				(font
					(size 1.27 1.27)
				)
				(justify mirror)
			)
		)
		(duplicate_pad_numbers_are_jumpers no)
		(fp_poly
			(pts
				(xy 0.2794 -0.1016) (xy -0.2794 -0.1016) (xy -0.2794 0.9906) (xy 0.2794 0.9906)
			)
			(stroke
				(width 0)
				(type default)
			)
			(fill no)
			(layer "B.CrtYd")
		)
		(fp_line
			(start -0.2794 0.9906)
			(end -0.2794 -0.1016)
			(stroke
				(width 0.1)
				(type default)
			)
			(layer "B.Fab")
		)
		(fp_line
			(start 0.2794 0.9906)
			(end -0.2794 0.9906)
			(stroke
				(width 0.1)
				(type default)
			)
			(layer "B.Fab")
		)
		(fp_line
			(start -0.2794 -0.1016)
			(end 0.2794 -0.1016)
			(stroke
				(width 0.1)
				(type default)
			)
			(layer "B.Fab")
		)
		(fp_line
			(start 0.2794 -0.1016)
			(end 0.2794 0.9906)
			(stroke
				(width 0.1)
				(type default)
			)
			(layer "B.Fab")
		)
		(pad "1" smd rect
			(at 0 0 90)
			(size 0.508 0.508)
			(layers "B.Cu" "B.Mask" "B.Paste")
			(net "P3V_BAT_SOURCE")
		)
		(pad "2" smd rect
			(at 0 0.889 90)
			(size 0.508 0.508)
			(layers "B.Cu" "B.Mask" "B.Paste")
			(net "A_P3V_BAT_R")
		)
		(zone
			(layer "B.Cu")
			(hatch none 0.5)
			(connect_pads
				(clearance 0)
			)
			(min_thickness 0.25)
			(keepout
				(tracks not_allowed)
				(vias allowed)
				(pads allowed)
				(copperpour not_allowed)
				(footprints allowed)
			)
			(placement
				(enabled no)
				(sheetname "")
			)
			(fill
				(thermal_gap 0.5)
				(thermal_bridge_width 0.5)
				(island_removal_mode 0)
			)
			(polygon
				(pts
					(xy 449.3514 -7.7978) (xy 449.3514 -8.3058) (xy 449.7324 -8.3058) (xy 449.7324 -7.7978)
				)
			)
		)
		(zone
			(layer "B.Cu")
			(hatch none 0.5)
			(connect_pads
				(clearance 0)
			)
			(min_thickness 0.25)
			(keepout
				(tracks allowed)
				(vias not_allowed)
				(pads allowed)
				(copperpour not_allowed)
				(footprints allowed)
			)
			(placement
				(enabled no)
				(sheetname "")
			)
			(fill
				(thermal_gap 0.5)
				(thermal_bridge_width 0.5)
				(island_removal_mode 0)
			)
			(polygon
				(pts
					(xy 449.7324 -7.7978) (xy 449.7324 -8.3058) (xy 449.3514 -8.3058) (xy 449.3514 -7.7978)
				)
			)
		)
	)
	(footprint ""
		(layer "B.Cu")
		(at 472.127326 -15.951962)
		(property "Reference" "C2U2"
			(at 0 0 0)
			(layer "B.SilkS")
			(hide yes)
			(effects
				(font
					(size 1.27 1.27)
				)
				(justify mirror)
			)
		)
		(property "Value" ""
			(at 0 0 0)
			(layer "B.Fab")
			(effects
				(font
					(size 1.27 1.27)
				)
				(justify mirror)
			)
		)
		(duplicate_pad_numbers_are_jumpers no)
		(fp_rect
			(start 0.7239 -0.2159)
			(end -0.7239 1.9939)
			(stroke
				(width 0)
				(type default)
			)
			(fill no)
			(layer "B.CrtYd")
		)
		(fp_line
			(start -0.7239 -0.2159)
			(end 0.7239 -0.2159)
			(stroke
				(width 0.1)
				(type default)
			)
			(layer "B.Fab")
		)
		(fp_line
			(start -0.7239 1.9939)
			(end -0.7239 -0.2159)
			(stroke
				(width 0.1)
				(type default)
			)
			(layer "B.Fab")
		)
		(fp_line
			(start 0.7239 -0.2159)
			(end 0.7239 1.9939)
			(stroke
				(width 0.1)
				(type default)
			)
			(layer "B.Fab")
		)
		(fp_line
			(start 0.7239 1.9939)
			(end -0.7239 1.9939)
			(stroke
				(width 0.1)
				(type default)
			)
			(layer "B.Fab")
		)
		(pad "1" smd rect
			(at 0 0 180)
			(size 1.27 1.016)
			(layers "B.Cu" "B.Mask" "B.Paste")
			(net "P3V3")
		)
		(pad "2" smd rect
			(at 0 1.778 180)
			(size 1.27 1.016)
			(layers "B.Cu" "B.Mask" "B.Paste")
			(net "GND")
		)
		(zone
			(layer "B.Cu")
			(hatch none 0.5)
			(connect_pads
				(clearance 0)
			)
			(min_thickness 0.25)
			(keepout
				(tracks not_allowed)
				(vias allowed)
				(pads allowed)
				(copperpour not_allowed)
				(footprints allowed)
			)
			(placement
				(enabled no)
				(sheetname "")
			)
			(fill
				(thermal_gap 0.5)
				(thermal_bridge_width 0.5)
				(island_removal_mode 0)
			)
			(polygon
				(pts
					(xy 472.762326 -15.443962) (xy 471.492326 -15.443962) (xy 471.492326 -14.681962) (xy 472.762326 -14.681962)
				)
			)
		)
	)
	(footprint ""
		(layer "B.Cu")
		(at 80.153002 -86.743286 -90)
		(property "Reference" "R8P2"
			(at 0 0 90)
			(layer "B.SilkS")
			(hide yes)
			(effects
				(font
					(size 1.27 1.27)
				)
				(justify mirror)
			)
		)
		(property "Value" ""
			(at 0 0 90)
			(layer "B.Fab")
			(effects
				(font
					(size 1.27 1.27)
				)
				(justify mirror)
			)
		)
		(duplicate_pad_numbers_are_jumpers no)
		(fp_poly
			(pts
				(xy 0.2794 -0.1016) (xy -0.2794 -0.1016) (xy -0.2794 0.9906) (xy 0.2794 0.9906)
			)
			(stroke
				(width 0)
				(type default)
			)
			(fill no)
			(layer "B.CrtYd")
		)
		(fp_line
			(start -0.2794 0.9906)
			(end -0.2794 -0.1016)
			(stroke
				(width 0.1)
				(type default)
			)
			(layer "B.Fab")
		)
		(fp_line
			(start 0.2794 0.9906)
			(end -0.2794 0.9906)
			(stroke
				(width 0.1)
				(type default)
			)
			(layer "B.Fab")
		)
		(fp_line
			(start -0.2794 -0.1016)
			(end 0.2794 -0.1016)
			(stroke
				(width 0.1)
				(type default)
			)
			(layer "B.Fab")
		)
		(fp_line
			(start 0.2794 -0.1016)
			(end 0.2794 0.9906)
			(stroke
				(width 0.1)
				(type default)
			)
			(layer "B.Fab")
		)
		(pad "1" smd rect
			(at 0 0 90)
			(size 0.508 0.508)
			(layers "B.Cu" "B.Mask" "B.Paste")
			(net "PD_CPU1_TEST13")
		)
		(pad "2" smd rect
			(at 0 0.889 90)
			(size 0.508 0.508)
			(layers "B.Cu" "B.Mask" "B.Paste")
			(net "GND")
		)
		(zone
			(layer "B.Cu")
			(hatch none 0.5)
			(connect_pads
				(clearance 0)
			)
			(min_thickness 0.25)
			(keepout
				(tracks not_allowed)
				(vias allowed)
				(pads allowed)
				(copperpour not_allowed)
				(footprints allowed)
			)
			(placement
				(enabled no)
				(sheetname "")
			)
			(fill
				(thermal_gap 0.5)
				(thermal_bridge_width 0.5)
				(island_removal_mode 0)
			)
			(polygon
				(pts
					(xy 79.518002 -86.489286) (xy 79.518002 -86.997286) (xy 79.899002 -86.997286) (xy 79.899002 -86.489286)
				)
			)
		)
		(zone
			(layer "B.Cu")
			(hatch none 0.5)
			(connect_pads
				(clearance 0)
			)
			(min_thickness 0.25)
			(keepout
				(tracks allowed)
				(vias not_allowed)
				(pads allowed)
				(copperpour not_allowed)
				(footprints allowed)
			)
			(placement
				(enabled no)
				(sheetname "")
			)
			(fill
				(thermal_gap 0.5)
				(thermal_bridge_width 0.5)
				(island_removal_mode 0)
			)
			(polygon
				(pts
					(xy 79.899002 -86.489286) (xy 79.899002 -86.997286) (xy 79.518002 -86.997286) (xy 79.518002 -86.489286)
				)
			)
		)
	)
)
